(kicad_pcb
	(version 20260206)
	(generator "pcbnew")
	(generator_version "10.0")
	(general
		(thickness 1.6)
		(legacy_teardrops no)
	)
	(paper "A4")
	(title_block
		(title "01162023_DA0F0TEBIF0_F0T_Expander_BD_F_brd_V02_OCP.brd")
		(comment 1 "Grand Teton / footprint 6619 of 9728 (PEX0), pads 1-116 of 2397")
	)
	(layers
		(0 "F.Cu" signal "TOP")
		(4 "In1.Cu" signal "GND")
		(6 "In2.Cu" signal "VCC")
		(8 "In3.Cu" signal "VCC1")
		(10 "In4.Cu" signal "GND1")
		(12 "In5.Cu" signal "IN1")
		(14 "In6.Cu" signal "GND2")
		(16 "In7.Cu" signal "IN2")
		(18 "In8.Cu" signal "GND3")
		(20 "In9.Cu" signal "IN3")
		(22 "In10.Cu" signal "GND4")
		(24 "In11.Cu" signal "IN4")
		(26 "In12.Cu" signal "GND5")
		(28 "In13.Cu" signal "IN5")
		(30 "In14.Cu" signal "GND6")
		(32 "In15.Cu" signal "IN6")
		(34 "In16.Cu" signal "GND7")
		(2 "B.Cu" signal "BOTTOM")
		(9 "F.Adhes" user "F.Adhesive")
		(11 "B.Adhes" user "B.Adhesive")
		(13 "F.Paste" user "Package Geometry/Pastemask Top")
		(15 "B.Paste" user "Package Geometry/Pastemask Bottom")
		(5 "F.SilkS" user "Ref Des/Silkscreen Top")
		(7 "B.SilkS" user "Ref Des/Silkscreen Bottom")
		(1 "F.Mask" user "Board Geometry/Soldermask Top")
		(3 "B.Mask" user "Board Geometry/Soldermask Bottom")
		(17 "Dwgs.User" user "User.Drawings")
		(19 "Cmts.User" user "User.Comments")
		(21 "Eco1.User" user "User.Eco1")
		(23 "Eco2.User" user "User.Eco2")
		(25 "Edge.Cuts" user "Board Geometry/Outline")
		(27 "Margin" user)
		(31 "F.CrtYd" user "Package Geometry/Place Bound Top")
		(29 "B.CrtYd" user "Package Geometry/Place Bound Bottom")
		(35 "F.Fab" user "Ref Des/Assembly Top")
		(33 "B.Fab" user "Ref Des/Assembly Bottom")
	)
	(footprint ""
		(layer "F.Cu")
		(at 59.649868 -295.89984)
		(property "Reference" "PEX0"
			(at -3.360166 35.566858 0)
			(unlocked yes)
			(layer "F.SilkS")
			(effects
				(font
					(size 2.032 1.524)
					(thickness 0.1524)
				)
				(justify left)
			)
		)
		(property "Value" ""
			(at 0 0 0)
			(layer "F.Fab")
			(effects
				(font
					(size 1.27 1.27)
				)
			)
		)
		(duplicate_pad_numbers_are_jumpers no)
		(pad "A2" smd circle
			(at -21.850096 -22.800056)
			(size 0.4572 0.4572)
			(layers "F.Cu" "F.Mask" "F.Paste")
			(net "GND")
		)
		(pad "A3" smd circle
			(at -20.899882 -22.800056)
			(size 0.4572 0.4572)
			(layers "F.Cu" "F.Mask" "F.Paste")
			(net "P5E_PEX0_STN7_RX_DN<123>")
		)
		(pad "A4" smd circle
			(at -19.949922 -22.800056)
			(size 0.4572 0.4572)
			(layers "F.Cu" "F.Mask" "F.Paste")
			(net "GND")
		)
		(pad "A5" smd circle
			(at -18.999962 -22.800056)
			(size 0.4572 0.4572)
			(layers "F.Cu" "F.Mask" "F.Paste")
			(net "P5E_PEX0_STN7_RX_DN<125>")
		)
		(pad "A6" smd circle
			(at -18.050002 -22.800056)
			(size 0.4572 0.4572)
			(layers "F.Cu" "F.Mask" "F.Paste")
			(net "GND")
		)
		(pad "A7" smd circle
			(at -17.100042 -22.800056)
			(size 0.4572 0.4572)
			(layers "F.Cu" "F.Mask" "F.Paste")
			(net "P5E_PEX0_STN7_RX_DN<127>")
		)
		(pad "A8" smd circle
			(at -16.150082 -22.800056)
			(size 0.4572 0.4572)
			(layers "F.Cu" "F.Mask" "F.Paste")
			(net "GND")
		)
		(pad "A9" smd circle
			(at -15.200122 -22.800056)
			(size 0.4572 0.4572)
			(layers "F.Cu" "F.Mask" "F.Paste")
			(net "P5E_PEX0_STN6_RX_DN<110>")
		)
		(pad "A10" smd circle
			(at -14.249908 -22.800056)
			(size 0.4572 0.4572)
			(layers "F.Cu" "F.Mask" "F.Paste")
			(net "GND")
		)
		(pad "A11" smd circle
			(at -13.299948 -22.800056)
			(size 0.4572 0.4572)
			(layers "F.Cu" "F.Mask" "F.Paste")
			(net "P5E_PEX0_STN6_RX_DN<108>")
		)
		(pad "A12" smd circle
			(at -12.349988 -22.800056)
			(size 0.4572 0.4572)
			(layers "F.Cu" "F.Mask" "F.Paste")
			(net "GND")
		)
		(pad "A13" smd circle
			(at -11.400028 -22.800056)
			(size 0.4572 0.4572)
			(layers "F.Cu" "F.Mask" "F.Paste")
			(net "P5E_PEX0_STN6_RX_DN<106>")
		)
		(pad "A14" smd circle
			(at -10.450068 -22.800056)
			(size 0.4572 0.4572)
			(layers "F.Cu" "F.Mask" "F.Paste")
			(net "GND")
		)
		(pad "A15" smd circle
			(at -9.500108 -22.800056)
			(size 0.4572 0.4572)
			(layers "F.Cu" "F.Mask" "F.Paste")
			(net "P5E_PEX0_STN6_RX_DN<104>")
		)
		(pad "A16" smd circle
			(at -8.549894 -22.800056)
			(size 0.4572 0.4572)
			(layers "F.Cu" "F.Mask" "F.Paste")
			(net "GND")
		)
		(pad "A17" smd circle
			(at -7.599934 -22.800056)
			(size 0.4572 0.4572)
			(layers "F.Cu" "F.Mask" "F.Paste")
			(net "P5E_PEX0_STN6_RX_DN<102>")
		)
		(pad "A18" smd circle
			(at -6.649974 -22.800056)
			(size 0.4572 0.4572)
			(layers "F.Cu" "F.Mask" "F.Paste")
			(net "GND")
		)
		(pad "A19" smd circle
			(at -5.700014 -22.800056)
			(size 0.4572 0.4572)
			(layers "F.Cu" "F.Mask" "F.Paste")
			(net "P5E_PEX0_STN6_RX_DN<100>")
		)
		(pad "A20" smd circle
			(at -4.750054 -22.800056)
			(size 0.4572 0.4572)
			(layers "F.Cu" "F.Mask" "F.Paste")
			(net "GND")
		)
		(pad "A21" smd circle
			(at -3.800094 -22.800056)
			(size 0.4572 0.4572)
			(layers "F.Cu" "F.Mask" "F.Paste")
			(net "P5E_PEX0_STN6_RX_DN<98>")
		)
		(pad "A22" smd circle
			(at -2.84988 -22.800056)
			(size 0.4572 0.4572)
			(layers "F.Cu" "F.Mask" "F.Paste")
			(net "GND")
		)
		(pad "A23" smd circle
			(at -1.89992 -22.800056)
			(size 0.4572 0.4572)
			(layers "F.Cu" "F.Mask" "F.Paste")
			(net "P5E_PEX0_STN6_RX_DN<96>")
		)
		(pad "A24" smd circle
			(at -0.94996 -22.800056)
			(size 0.4572 0.4572)
			(layers "F.Cu" "F.Mask" "F.Paste")
			(net "GND")
		)
		(pad "A25" smd circle
			(at 0 -22.800056)
			(size 0.4572 0.4572)
			(layers "F.Cu" "F.Mask" "F.Paste")
			(net "P5E_PEX0_STN5_RX_DN<81>")
		)
		(pad "A26" smd circle
			(at 0.94996 -22.800056)
			(size 0.4572 0.4572)
			(layers "F.Cu" "F.Mask" "F.Paste")
			(net "GND")
		)
		(pad "A27" smd circle
			(at 1.89992 -22.800056)
			(size 0.4572 0.4572)
			(layers "F.Cu" "F.Mask" "F.Paste")
			(net "P5E_PEX0_STN5_RX_DN<83>")
		)
		(pad "A28" smd circle
			(at 2.84988 -22.800056)
			(size 0.4572 0.4572)
			(layers "F.Cu" "F.Mask" "F.Paste")
			(net "GND")
		)
		(pad "A29" smd circle
			(at 3.800094 -22.800056)
			(size 0.4572 0.4572)
			(layers "F.Cu" "F.Mask" "F.Paste")
			(net "P5E_PEX0_STN5_RX_DN<85>")
		)
		(pad "A30" smd circle
			(at 4.750054 -22.800056)
			(size 0.4572 0.4572)
			(layers "F.Cu" "F.Mask" "F.Paste")
			(net "GND")
		)
		(pad "A31" smd circle
			(at 5.700014 -22.800056)
			(size 0.4572 0.4572)
			(layers "F.Cu" "F.Mask" "F.Paste")
			(net "P5E_PEX0_STN5_RX_DN<87>")
		)
		(pad "A32" smd circle
			(at 6.649974 -22.800056)
			(size 0.4572 0.4572)
			(layers "F.Cu" "F.Mask" "F.Paste")
			(net "GND")
		)
		(pad "A33" smd circle
			(at 7.599934 -22.800056)
			(size 0.4572 0.4572)
			(layers "F.Cu" "F.Mask" "F.Paste")
			(net "P5E_PEX0_STN5_RX_DN<89>")
		)
		(pad "A34" smd circle
			(at 8.549894 -22.800056)
			(size 0.4572 0.4572)
			(layers "F.Cu" "F.Mask" "F.Paste")
			(net "GND")
		)
		(pad "A35" smd circle
			(at 9.500108 -22.800056)
			(size 0.4572 0.4572)
			(layers "F.Cu" "F.Mask" "F.Paste")
			(net "P5E_PEX0_STN5_RX_DN<91>")
		)
		(pad "A36" smd circle
			(at 10.450068 -22.800056)
			(size 0.4572 0.4572)
			(layers "F.Cu" "F.Mask" "F.Paste")
			(net "GND")
		)
		(pad "A37" smd circle
			(at 11.400028 -22.800056)
			(size 0.4572 0.4572)
			(layers "F.Cu" "F.Mask" "F.Paste")
			(net "P5E_PEX0_STN5_RX_DN<93>")
		)
		(pad "A38" smd circle
			(at 12.349988 -22.800056)
			(size 0.4572 0.4572)
			(layers "F.Cu" "F.Mask" "F.Paste")
			(net "GND")
		)
		(pad "A39" smd circle
			(at 13.299948 -22.800056)
			(size 0.4572 0.4572)
			(layers "F.Cu" "F.Mask" "F.Paste")
			(net "P5E_PEX0_STN5_RX_DN<95>")
		)
		(pad "A40" smd circle
			(at 14.249908 -22.800056)
			(size 0.4572 0.4572)
			(layers "F.Cu" "F.Mask" "F.Paste")
			(net "GND")
		)
		(pad "A41" smd circle
			(at 15.200122 -22.800056)
			(size 0.4572 0.4572)
			(layers "F.Cu" "F.Mask" "F.Paste")
			(net "P5E_PEX0_STN4_RX_DN<78>")
		)
		(pad "A42" smd circle
			(at 16.150082 -22.800056)
			(size 0.4572 0.4572)
			(layers "F.Cu" "F.Mask" "F.Paste")
			(net "GND")
		)
		(pad "A43" smd circle
			(at 17.100042 -22.800056)
			(size 0.4572 0.4572)
			(layers "F.Cu" "F.Mask" "F.Paste")
			(net "P5E_PEX0_STN4_RX_DN<76>")
		)
		(pad "A44" smd circle
			(at 18.050002 -22.800056)
			(size 0.4572 0.4572)
			(layers "F.Cu" "F.Mask" "F.Paste")
			(net "GND")
		)
		(pad "A45" smd circle
			(at 18.999962 -22.800056)
			(size 0.4572 0.4572)
			(layers "F.Cu" "F.Mask" "F.Paste")
			(net "P5E_PEX0_STN4_RX_DN<74>")
		)
		(pad "A46" smd circle
			(at 19.949922 -22.800056)
			(size 0.4572 0.4572)
			(layers "F.Cu" "F.Mask" "F.Paste")
			(net "GND")
		)
		(pad "A47" smd circle
			(at 20.899882 -22.800056)
			(size 0.4572 0.4572)
			(layers "F.Cu" "F.Mask" "F.Paste")
			(net "P5E_PEX0_STN4_RX_DN<72>")
		)
		(pad "A48" smd circle
			(at 21.850096 -22.800056)
			(size 0.4572 0.4572)
			(layers "F.Cu" "F.Mask" "F.Paste")
			(net "GND")
		)
		(pad "AA1" smd circle
			(at -22.800056 -3.800094)
			(size 0.4572 0.4572)
			(layers "F.Cu" "F.Mask" "F.Paste")
			(net "CLK_100M_PEX0_REF_R_DN")
		)
		(pad "AA2" smd circle
			(at -21.850096 -3.800094)
			(size 0.4572 0.4572)
			(layers "F.Cu" "F.Mask" "F.Paste")
			(net "CLK_100M_PEX0_REF_R_DP")
		)
		(pad "AA3" smd circle
			(at -20.899882 -3.800094)
			(size 0.4572 0.4572)
			(layers "F.Cu" "F.Mask" "F.Paste")
			(net "GND")
		)
		(pad "AA4" smd circle
			(at -19.949922 -3.800094)
			(size 0.4572 0.4572)
			(layers "F.Cu" "F.Mask" "F.Paste")
			(net "GND")
		)
		(pad "AA5" smd circle
			(at -18.999962 -3.800094)
			(size 0.4572 0.4572)
			(layers "F.Cu" "F.Mask" "F.Paste")
			(net "GND")
		)
		(pad "AA6" smd circle
			(at -18.050002 -3.800094)
			(size 0.4572 0.4572)
			(layers "F.Cu" "F.Mask" "F.Paste")
			(net "GND")
		)
		(pad "AA7" smd circle
			(at -17.100042 -3.800094)
			(size 0.4572 0.4572)
			(layers "F.Cu" "F.Mask" "F.Paste")
			(net "GND")
		)
		(pad "AA8" smd circle
			(at -16.150082 -3.800094)
			(size 0.4572 0.4572)
			(layers "F.Cu" "F.Mask" "F.Paste")
			(net "GND")
		)
		(pad "AA9" smd circle
			(at -15.200122 -3.800094)
			(size 0.4572 0.4572)
			(layers "F.Cu" "F.Mask" "F.Paste")
			(net "GND")
		)
		(pad "AA10" smd circle
			(at -14.249908 -3.800094)
			(size 0.4572 0.4572)
			(layers "F.Cu" "F.Mask" "F.Paste")
			(net "P1V8_VDDA_PEX0")
		)
		(pad "AA11" smd circle
			(at -13.299948 -3.800094)
			(size 0.4572 0.4572)
			(layers "F.Cu" "F.Mask" "F.Paste")
			(net "GND")
		)
		(pad "AA12" smd circle
			(at -12.349988 -3.800094)
			(size 0.4572 0.4572)
			(layers "F.Cu" "F.Mask" "F.Paste")
			(net "GND")
		)
		(pad "AA13" smd circle
			(at -11.400028 -3.800094)
			(size 0.4572 0.4572)
			(layers "F.Cu" "F.Mask" "F.Paste")
			(net "PCEPLL0_VDDA18_PEX0")
		)
		(pad "AA14" smd circle
			(at -10.450068 -3.800094)
			(size 0.4572 0.4572)
			(layers "F.Cu" "F.Mask" "F.Paste")
			(net "GND")
		)
		(pad "AA15" smd circle
			(at -9.500108 -3.800094)
			(size 0.4572 0.4572)
			(layers "F.Cu" "F.Mask" "F.Paste")
			(net "P0V8_PEX0")
		)
		(pad "AA16" smd circle
			(at -8.549894 -3.800094)
			(size 0.4572 0.4572)
			(layers "F.Cu" "F.Mask" "F.Paste")
			(net "GND")
		)
		(pad "AA17" smd circle
			(at -7.599934 -3.800094)
			(size 0.4572 0.4572)
			(layers "F.Cu" "F.Mask" "F.Paste")
			(net "GND")
		)
		(pad "AA18" smd circle
			(at -6.649974 -3.800094)
			(size 0.4572 0.4572)
			(layers "F.Cu" "F.Mask" "F.Paste")
			(net "GND")
		)
		(pad "AA19" smd circle
			(at -5.700014 -3.800094)
			(size 0.4572 0.4572)
			(layers "F.Cu" "F.Mask" "F.Paste")
			(net "GND")
		)
		(pad "AA20" smd circle
			(at -4.750054 -3.800094)
			(size 0.4572 0.4572)
			(layers "F.Cu" "F.Mask" "F.Paste")
			(net "GND")
		)
		(pad "AA21" smd circle
			(at -3.800094 -3.800094)
			(size 0.4572 0.4572)
			(layers "F.Cu" "F.Mask" "F.Paste")
			(net "GND")
		)
		(pad "AA22" smd circle
			(at -2.84988 -3.800094)
			(size 0.4572 0.4572)
			(layers "F.Cu" "F.Mask" "F.Paste")
			(net "GND")
		)
		(pad "AA23" smd circle
			(at -1.89992 -3.800094)
			(size 0.4572 0.4572)
			(layers "F.Cu" "F.Mask" "F.Paste")
			(net "GND")
		)
		(pad "AA24" smd circle
			(at -0.94996 -3.800094)
			(size 0.4572 0.4572)
			(layers "F.Cu" "F.Mask" "F.Paste")
			(net "GND")
		)
		(pad "AA25" smd circle
			(at 0 -3.800094)
			(size 0.4572 0.4572)
			(layers "F.Cu" "F.Mask" "F.Paste")
			(net "GND")
		)
		(pad "AA26" smd circle
			(at 0.94996 -3.800094)
			(size 0.4572 0.4572)
			(layers "F.Cu" "F.Mask" "F.Paste")
			(net "GND")
		)
		(pad "AA27" smd circle
			(at 1.89992 -3.800094)
			(size 0.4572 0.4572)
			(layers "F.Cu" "F.Mask" "F.Paste")
			(net "GND")
		)
		(pad "AA28" smd circle
			(at 2.84988 -3.800094)
			(size 0.4572 0.4572)
			(layers "F.Cu" "F.Mask" "F.Paste")
			(net "GND")
		)
		(pad "AA29" smd circle
			(at 3.800094 -3.800094)
			(size 0.4572 0.4572)
			(layers "F.Cu" "F.Mask" "F.Paste")
			(net "GND")
		)
		(pad "AA30" smd circle
			(at 4.750054 -3.800094)
			(size 0.4572 0.4572)
			(layers "F.Cu" "F.Mask" "F.Paste")
			(net "GND")
		)
		(pad "AA31" smd circle
			(at 5.700014 -3.800094)
			(size 0.4572 0.4572)
			(layers "F.Cu" "F.Mask" "F.Paste")
			(net "GND")
		)
		(pad "AA32" smd circle
			(at 6.649974 -3.800094)
			(size 0.4572 0.4572)
			(layers "F.Cu" "F.Mask" "F.Paste")
			(net "GND")
		)
		(pad "AA33" smd circle
			(at 7.599934 -3.800094)
			(size 0.4572 0.4572)
			(layers "F.Cu" "F.Mask" "F.Paste")
			(net "GND")
		)
		(pad "AA34" smd circle
			(at 8.549894 -3.800094)
			(size 0.4572 0.4572)
			(layers "F.Cu" "F.Mask" "F.Paste")
			(net "P1V8_VDDA_PEX0")
		)
		(pad "AA35" smd circle
			(at 9.500108 -3.800094)
			(size 0.4572 0.4572)
			(layers "F.Cu" "F.Mask" "F.Paste")
			(net "Net_480")
		)
		(pad "AA36" smd circle
			(at 10.450068 -3.800094)
			(size 0.4572 0.4572)
			(layers "F.Cu" "F.Mask" "F.Paste")
			(net "GND")
		)
		(pad "AA37" smd circle
			(at 11.400028 -3.800094)
			(size 0.4572 0.4572)
			(layers "F.Cu" "F.Mask" "F.Paste")
			(net "P1V8_VDDA_PEX0")
		)
		(pad "AA38" smd circle
			(at 12.349988 -3.800094)
			(size 0.4572 0.4572)
			(layers "F.Cu" "F.Mask" "F.Paste")
			(net "GND")
		)
		(pad "AA39" smd circle
			(at 13.299948 -3.800094)
			(size 0.4572 0.4572)
			(layers "F.Cu" "F.Mask" "F.Paste")
			(net "PEX0_ADCTEMP_VINP1")
		)
		(pad "AA40" smd circle
			(at 14.249908 -3.800094)
			(size 0.4572 0.4572)
			(layers "F.Cu" "F.Mask" "F.Paste")
			(net "GND")
		)
		(pad "AA41" smd circle
			(at 15.200122 -3.800094)
			(size 0.4572 0.4572)
			(layers "F.Cu" "F.Mask" "F.Paste")
			(net "GND")
		)
		(pad "AA42" smd circle
			(at 16.150082 -3.800094)
			(size 0.4572 0.4572)
			(layers "F.Cu" "F.Mask" "F.Paste")
			(net "GND")
		)
		(pad "AA43" smd circle
			(at 17.100042 -3.800094)
			(size 0.4572 0.4572)
			(layers "F.Cu" "F.Mask" "F.Paste")
			(net "Net_2818")
		)
		(pad "AA44" smd circle
			(at 18.050002 -3.800094)
			(size 0.4572 0.4572)
			(layers "F.Cu" "F.Mask" "F.Paste")
			(net "Net_2802")
		)
		(pad "AA45" smd circle
			(at 18.999962 -3.800094)
			(size 0.4572 0.4572)
			(layers "F.Cu" "F.Mask" "F.Paste")
			(net "GND")
		)
		(pad "AA46" smd circle
			(at 19.949922 -3.800094)
			(size 0.4572 0.4572)
			(layers "F.Cu" "F.Mask" "F.Paste")
			(net "Net_2786")
		)
		(pad "AA47" smd circle
			(at 20.899882 -3.800094)
			(size 0.4572 0.4572)
			(layers "F.Cu" "F.Mask" "F.Paste")
			(net "Net_2770")
		)
		(pad "AA48" smd circle
			(at 21.850096 -3.800094)
			(size 0.4572 0.4572)
			(layers "F.Cu" "F.Mask" "F.Paste")
			(net "GND")
		)
		(pad "AA49" smd circle
			(at 22.800056 -3.800094)
			(size 0.4572 0.4572)
			(layers "F.Cu" "F.Mask" "F.Paste")
			(net "GND")
		)
		(pad "AB1" smd circle
			(at -22.800056 -2.84988)
			(size 0.4572 0.4572)
			(layers "F.Cu" "F.Mask" "F.Paste")
			(net "GND")
		)
		(pad "AB2" smd circle
			(at -21.850096 -2.84988)
			(size 0.4572 0.4572)
			(layers "F.Cu" "F.Mask" "F.Paste")
			(net "GND")
		)
		(pad "AB3" smd circle
			(at -20.899882 -2.84988)
			(size 0.4572 0.4572)
			(layers "F.Cu" "F.Mask" "F.Paste")
			(net "GND")
		)
		(pad "AB4" smd circle
			(at -19.949922 -2.84988)
			(size 0.4572 0.4572)
			(layers "F.Cu" "F.Mask" "F.Paste")
			(net "CLK_100M_DB800ZL_PEX0_S0_R_DN")
		)
		(pad "AB5" smd circle
			(at -18.999962 -2.84988)
			(size 0.4572 0.4572)
			(layers "F.Cu" "F.Mask" "F.Paste")
			(net "CLK_100M_DB800ZL_PEX0_S0_R_DP")
		)
		(pad "AB6" smd circle
			(at -18.050002 -2.84988)
			(size 0.4572 0.4572)
			(layers "F.Cu" "F.Mask" "F.Paste")
			(net "GND")
		)
		(pad "AB7" smd circle
			(at -17.100042 -2.84988)
			(size 0.4572 0.4572)
			(layers "F.Cu" "F.Mask" "F.Paste")
			(net "Net_2914")
		)
		(pad "AB8" smd circle
			(at -16.150082 -2.84988)
			(size 0.4572 0.4572)
			(layers "F.Cu" "F.Mask" "F.Paste")
			(net "Net_2913")
		)
		(pad "AB9" smd circle
			(at -15.200122 -2.84988)
			(size 0.4572 0.4572)
			(layers "F.Cu" "F.Mask" "F.Paste")
			(net "GND")
		)
		(pad "AB10" smd circle
			(at -14.249908 -2.84988)
			(size 0.4572 0.4572)
			(layers "F.Cu" "F.Mask" "F.Paste")
			(net "P1V8_VDDA_PEX0")
		)
		(pad "AB11" smd circle
			(at -13.299948 -2.84988)
			(size 0.4572 0.4572)
			(layers "F.Cu" "F.Mask" "F.Paste")
			(net "GND")
		)
		(pad "AB12" smd circle
			(at -12.349988 -2.84988)
			(size 0.4572 0.4572)
			(layers "F.Cu" "F.Mask" "F.Paste")
			(net "PCEPLL1_VDDA18_PEX0")
		)
		(pad "AB13" smd circle
			(at -11.400028 -2.84988)
			(size 0.4572 0.4572)
			(layers "F.Cu" "F.Mask" "F.Paste")
			(net "GND")
		)
		(pad "AB14" smd circle
			(at -10.450068 -2.84988)
			(size 0.4572 0.4572)
			(layers "F.Cu" "F.Mask" "F.Paste")
			(net "P0V8_PEX0")
		)
		(pad "AB15" smd circle
			(at -9.500108 -2.84988)
			(size 0.4572 0.4572)
			(layers "F.Cu" "F.Mask" "F.Paste")
			(net "GND")
		)
		(pad "AB16" smd circle
			(at -8.549894 -2.84988)
			(size 0.4572 0.4572)
			(layers "F.Cu" "F.Mask" "F.Paste")
			(net "P0V8_SERDES_VDDA_PEX0")
		)
		(pad "AB17" smd circle
			(at -7.599934 -2.84988)
			(size 0.4572 0.4572)
			(layers "F.Cu" "F.Mask" "F.Paste")
			(net "P0V8_SERDES_VDDA_PEX0")
		)
		(pad "AB18" smd circle
			(at -6.649974 -2.84988)
			(size 0.4572 0.4572)
			(layers "F.Cu" "F.Mask" "F.Paste")
			(net "P0V8_SERDES_VDDA_PEX0")
		)
		(pad "AB19" smd circle
			(at -5.700014 -2.84988)
			(size 0.4572 0.4572)
			(layers "F.Cu" "F.Mask" "F.Paste")
			(net "P0V8_SERDES_VDDA_PEX0")
		)
		(pad "AB20" smd circle
			(at -4.750054 -2.84988)
			(size 0.4572 0.4572)
			(layers "F.Cu" "F.Mask" "F.Paste")
			(net "P0V8_SERDES_VDDA_PEX0")
		)
	)
)
